(kicad_pcb
	(version 20260206)
	(generator "pcbnew")
	(generator_version "10.0")
	(general
		(thickness 1.6)
		(legacy_teardrops no)
	)
	(paper "A4")
	(title_block
		(title "04192023_DAF0TMB3IC0_F0TG_MB_C_brd_V02_OCP.brd")
		(comment 1 "Grand Teton / footprint 4922 of 8354 (J35), pads 110-175 of 175")
	)
	(layers
		(0 "F.Cu" signal "TOP")
		(4 "In1.Cu" signal "GND")
		(6 "In2.Cu" signal "IN1")
		(8 "In3.Cu" signal "GND1")
		(10 "In4.Cu" signal "IN2")
		(12 "In5.Cu" signal "GND2")
		(14 "In6.Cu" signal "IN3")
		(16 "In7.Cu" signal "GND3")
		(18 "In8.Cu" signal "VCC")
		(20 "In9.Cu" signal "VCC1")
		(22 "In10.Cu" signal "GND4")
		(24 "In11.Cu" signal "IN4")
		(26 "In12.Cu" signal "GND5")
		(28 "In13.Cu" signal "IN5")
		(30 "In14.Cu" signal "GND6")
		(32 "In15.Cu" signal "IN6")
		(34 "In16.Cu" signal "GND7")
		(2 "B.Cu" signal "BOTTOM")
		(9 "F.Adhes" user "F.Adhesive")
		(11 "B.Adhes" user "B.Adhesive")
		(13 "F.Paste" user "Package Geometry/Pastemask Top")
		(15 "B.Paste" user "Package Geometry/Pastemask Bottom")
		(5 "F.SilkS" user "Ref Des/Silkscreen Top")
		(7 "B.SilkS" user "Ref Des/Silkscreen Bottom")
		(1 "F.Mask" user "Board Geometry/Soldermask Top")
		(3 "B.Mask" user "Board Geometry/Soldermask Bottom")
		(17 "Dwgs.User" user "User.Drawings")
		(19 "Cmts.User" user "User.Comments")
		(21 "Eco1.User" user "User.Eco1")
		(23 "Eco2.User" user "User.Eco2")
		(25 "Edge.Cuts" user "Board Geometry/Outline")
		(27 "Margin" user)
		(31 "F.CrtYd" user "Package Geometry/Place Bound Top")
		(29 "B.CrtYd" user "Package Geometry/Place Bound Bottom")
		(35 "F.Fab" user "Ref Des/Assembly Top")
		(33 "B.Fab" user "Ref Des/Assembly Bottom")
	)
	(footprint ""
		(layer "F.Cu")
		(at 47.401988 -5.569966 -90)
		(property "Reference" "J35"
			(at -8.0772 -20.659598 0)
			(unlocked yes)
			(layer "F.SilkS")
			(effects
				(font
					(size 0.7874 0.5842)
					(thickness 0.1524)
				)
				(justify left)
			)
		)
		(property "Value" ""
			(at 0 0 270)
			(layer "F.Fab")
			(effects
				(font
					(size 1.27 1.27)
				)
			)
		)
		(duplicate_pad_numbers_are_jumpers no)
		(pad "B38" smd rect
			(at -5.700014 7.14502 180)
			(size 0.381 1.4478)
			(layers "F.Cu" "F.Mask" "F.Paste")
			(net "GND")
		)
		(pad "B39" smd rect
			(at -5.700014 7.744968 180)
			(size 0.381 1.4478)
			(layers "F.Cu" "F.Mask" "F.Paste")
			(net "P5E_CPU1_G1_TX_C_DP<7>")
		)
		(pad "B40" smd rect
			(at -5.700014 8.344916 180)
			(size 0.381 1.4478)
			(layers "F.Cu" "F.Mask" "F.Paste")
			(net "P5E_CPU1_G1_TX_C_DN<7>")
		)
		(pad "B41" smd rect
			(at -5.700014 8.945118 180)
			(size 0.381 1.4478)
			(layers "F.Cu" "F.Mask" "F.Paste")
			(net "GND")
		)
		(pad "B42" smd rect
			(at -5.700014 9.545066 180)
			(size 0.381 1.4478)
			(layers "F.Cu" "F.Mask" "F.Paste")
			(net "OCP_V3_2_PRSNT0_R_N")
		)
		(pad "B43" smd rect
			(at -5.700014 14.454886 180)
			(size 0.381 1.4478)
			(layers "F.Cu" "F.Mask" "F.Paste")
			(net "GND")
		)
		(pad "B44" smd rect
			(at -5.700014 15.055088 180)
			(size 0.381 1.4478)
			(layers "F.Cu" "F.Mask" "F.Paste")
			(net "P5E_CPU1_G1_TX_C_DP<8>")
		)
		(pad "B45" smd rect
			(at -5.700014 15.655036 180)
			(size 0.381 1.4478)
			(layers "F.Cu" "F.Mask" "F.Paste")
			(net "P5E_CPU1_G1_TX_C_DN<8>")
		)
		(pad "B46" smd rect
			(at -5.700014 16.254984 180)
			(size 0.381 1.4478)
			(layers "F.Cu" "F.Mask" "F.Paste")
			(net "GND")
		)
		(pad "B47" smd rect
			(at -5.700014 16.854932 180)
			(size 0.381 1.4478)
			(layers "F.Cu" "F.Mask" "F.Paste")
			(net "P5E_CPU1_G1_TX_C_DP<9>")
		)
		(pad "B48" smd rect
			(at -5.700014 17.45488 180)
			(size 0.381 1.4478)
			(layers "F.Cu" "F.Mask" "F.Paste")
			(net "P5E_CPU1_G1_TX_C_DN<9>")
		)
		(pad "B49" smd rect
			(at -5.700014 18.055082 180)
			(size 0.381 1.4478)
			(layers "F.Cu" "F.Mask" "F.Paste")
			(net "GND")
		)
		(pad "B50" smd rect
			(at -5.700014 18.65503 180)
			(size 0.381 1.4478)
			(layers "F.Cu" "F.Mask" "F.Paste")
			(net "P5E_CPU1_G1_TX_C_DP<10>")
		)
		(pad "B51" smd rect
			(at -5.700014 19.254978 180)
			(size 0.381 1.4478)
			(layers "F.Cu" "F.Mask" "F.Paste")
			(net "P5E_CPU1_G1_TX_C_DN<10>")
		)
		(pad "B52" smd rect
			(at -5.700014 19.854926 180)
			(size 0.381 1.4478)
			(layers "F.Cu" "F.Mask" "F.Paste")
			(net "GND")
		)
		(pad "B53" smd rect
			(at -5.700014 20.455128 180)
			(size 0.381 1.4478)
			(layers "F.Cu" "F.Mask" "F.Paste")
			(net "P5E_CPU1_G1_TX_C_DP<11>")
		)
		(pad "B54" smd rect
			(at -5.700014 21.055076 180)
			(size 0.381 1.4478)
			(layers "F.Cu" "F.Mask" "F.Paste")
			(net "P5E_CPU1_G1_TX_C_DN<11>")
		)
		(pad "B55" smd rect
			(at -5.700014 21.655024 180)
			(size 0.381 1.4478)
			(layers "F.Cu" "F.Mask" "F.Paste")
			(net "GND")
		)
		(pad "B56" smd rect
			(at -5.700014 22.254972 180)
			(size 0.381 1.4478)
			(layers "F.Cu" "F.Mask" "F.Paste")
			(net "P5E_CPU1_G1_TX_C_DP<12>")
		)
		(pad "B57" smd rect
			(at -5.700014 22.85492 180)
			(size 0.381 1.4478)
			(layers "F.Cu" "F.Mask" "F.Paste")
			(net "P5E_CPU1_G1_TX_C_DN<12>")
		)
		(pad "B58" smd rect
			(at -5.700014 23.455122 180)
			(size 0.381 1.4478)
			(layers "F.Cu" "F.Mask" "F.Paste")
			(net "GND")
		)
		(pad "B59" smd rect
			(at -5.700014 24.05507 180)
			(size 0.381 1.4478)
			(layers "F.Cu" "F.Mask" "F.Paste")
			(net "P5E_CPU1_G1_TX_C_DP<13>")
		)
		(pad "B60" smd rect
			(at -5.700014 24.655018 180)
			(size 0.381 1.4478)
			(layers "F.Cu" "F.Mask" "F.Paste")
			(net "P5E_CPU1_G1_TX_C_DN<13>")
		)
		(pad "B61" smd rect
			(at -5.700014 25.254966 180)
			(size 0.381 1.4478)
			(layers "F.Cu" "F.Mask" "F.Paste")
			(net "GND")
		)
		(pad "B62" smd rect
			(at -5.700014 25.854914 180)
			(size 0.381 1.4478)
			(layers "F.Cu" "F.Mask" "F.Paste")
			(net "P5E_CPU1_G1_TX_C_DP<14>")
		)
		(pad "B63" smd rect
			(at -5.700014 26.455116 180)
			(size 0.381 1.4478)
			(layers "F.Cu" "F.Mask" "F.Paste")
			(net "P5E_CPU1_G1_TX_C_DN<14>")
		)
		(pad "B64" smd rect
			(at -5.700014 27.055064 180)
			(size 0.381 1.4478)
			(layers "F.Cu" "F.Mask" "F.Paste")
			(net "GND")
		)
		(pad "B65" smd rect
			(at -5.700014 27.655012 180)
			(size 0.381 1.4478)
			(layers "F.Cu" "F.Mask" "F.Paste")
			(net "P5E_CPU1_G1_TX_C_DP<15>")
		)
		(pad "B66" smd rect
			(at -5.700014 28.25496 180)
			(size 0.381 1.4478)
			(layers "F.Cu" "F.Mask" "F.Paste")
			(net "P5E_CPU1_G1_TX_C_DN<15>")
		)
		(pad "B67" smd rect
			(at -5.700014 28.854908 180)
			(size 0.381 1.4478)
			(layers "F.Cu" "F.Mask" "F.Paste")
			(net "GND")
		)
		(pad "B68" smd rect
			(at -5.700014 29.45511 180)
			(size 0.381 1.4478)
			(layers "F.Cu" "F.Mask" "F.Paste")
			(net "TP_OCP_V3_2_B68")
		)
		(pad "B69" smd rect
			(at -5.700014 30.055058 180)
			(size 0.381 1.4478)
			(layers "F.Cu" "F.Mask" "F.Paste")
			(net "TP_OCP_V3_2_B69")
		)
		(pad "B70" smd rect
			(at -5.700014 30.655006 180)
			(size 0.381 1.4478)
			(layers "F.Cu" "F.Mask" "F.Paste")
			(net "OCP_V3_2_PRSNT3_R_N")
		)
		(pad "G1" thru_hole circle
			(at 2.400046 -32.759904 180)
			(size 1.6256 1.6256)
			(drill 1.1176)
			(layers "*.Cu" "*.Mask")
			(remove_unused_layers no)
			(net "GND")
			(clearance 0)
		)
		(pad "G2" thru_hole circle
			(at 2.400046 -20.379944 180)
			(size 1.6256 1.6256)
			(drill 1.1176)
			(layers "*.Cu" "*.Mask")
			(remove_unused_layers no)
			(net "GND")
			(clearance 0)
		)
		(pad "G3" thru_hole circle
			(at 2.400046 0 180)
			(size 1.6256 1.6256)
			(drill 1.1176)
			(layers "*.Cu" "*.Mask")
			(remove_unused_layers no)
			(net "GND")
			(clearance 0)
		)
		(pad "G4" thru_hole circle
			(at 2.400046 12.5349 180)
			(size 1.6256 1.6256)
			(drill 1.1176)
			(layers "*.Cu" "*.Mask")
			(remove_unused_layers no)
			(net "GND")
			(clearance 0)
		)
		(pad "G5" thru_hole circle
			(at 2.400046 32.759904 180)
			(size 1.6256 1.6256)
			(drill 1.1176)
			(layers "*.Cu" "*.Mask")
			(remove_unused_layers no)
			(net "GND")
			(clearance 0)
		)
		(pad "OA1" smd rect
			(at -2.750058 -30.660086 180)
			(size 0.381 1.4478)
			(layers "F.Cu" "F.Mask" "F.Paste")
			(net "RST_PERST2_OCP_V3_2_N")
		)
		(pad "OA2" smd rect
			(at -2.750058 -30.059884 180)
			(size 0.381 1.4478)
			(layers "F.Cu" "F.Mask" "F.Paste")
			(net "RST_PERST3_OCP_V3_2_N")
		)
		(pad "OA3" smd rect
			(at -2.750058 -29.459936 180)
			(size 0.381 1.4478)
			(layers "F.Cu" "F.Mask" "F.Paste")
			(net "IRQ_LVC3_OCP_V3_2_WAKE_N")
		)
		(pad "OA4" smd rect
			(at -2.750058 -28.859988 180)
			(size 0.381 1.4478)
			(layers "F.Cu" "F.Mask" "F.Paste")
			(net "OCP_V3_2_ISO1_RBT_ARB_IN")
		)
		(pad "OA5" smd rect
			(at -2.750058 -28.26004 180)
			(size 0.381 1.4478)
			(layers "F.Cu" "F.Mask" "F.Paste")
			(net "OCP_V3_2_ISO2_RBT_ARB_OUT")
		)
		(pad "OA6" smd rect
			(at -2.750058 -27.660092 180)
			(size 0.381 1.4478)
			(layers "F.Cu" "F.Mask" "F.Paste")
			(net "OCP_V3_2_ID1")
		)
		(pad "OA7" smd rect
			(at -2.750058 -27.05989 180)
			(size 0.381 1.4478)
			(layers "F.Cu" "F.Mask" "F.Paste")
			(net "NCSI_OCP_V3_2_TX_EN")
		)
		(pad "OA8" smd rect
			(at -2.750058 -26.459942 180)
			(size 0.381 1.4478)
			(layers "F.Cu" "F.Mask" "F.Paste")
			(net "NCSI_OCP_V3_2_TXD1")
		)
		(pad "OA9" smd rect
			(at -2.750058 -25.859994 180)
			(size 0.381 1.4478)
			(layers "F.Cu" "F.Mask" "F.Paste")
			(net "NCSI_OCP_V3_2_TXD0")
		)
		(pad "OA10" smd rect
			(at -2.750058 -25.260046 180)
			(size 0.381 1.4478)
			(layers "F.Cu" "F.Mask" "F.Paste")
			(net "GND")
		)
		(pad "OA11" smd rect
			(at -2.750058 -24.660098 180)
			(size 0.381 1.4478)
			(layers "F.Cu" "F.Mask" "F.Paste")
			(net "CLK_100M_CPU1_CLK05_DN")
		)
		(pad "OA12" smd rect
			(at -2.750058 -24.059896 180)
			(size 0.381 1.4478)
			(layers "F.Cu" "F.Mask" "F.Paste")
			(net "CLK_100M_CPU1_CLK05_DP")
		)
		(pad "OA13" smd rect
			(at -2.750058 -23.459948 180)
			(size 0.381 1.4478)
			(layers "F.Cu" "F.Mask" "F.Paste")
			(net "GND")
		)
		(pad "OA14" smd rect
			(at -2.750058 -22.86 180)
			(size 0.381 1.4478)
			(layers "F.Cu" "F.Mask" "F.Paste")
			(net "CLK_50M_NCSI_OCP_V3_2_ISO")
		)
		(pad "OB1" smd rect
			(at -5.700014 -30.660086 180)
			(size 0.381 1.4478)
			(layers "F.Cu" "F.Mask" "F.Paste")
			(net "FM_OCP_V3_2_PWR_GOOD")
		)
		(pad "OB2" smd rect
			(at -5.700014 -30.059884 180)
			(size 0.381 1.4478)
			(layers "F.Cu" "F.Mask" "F.Paste")
			(net "OCP_V3_2_MAIN_PWR_EN_R")
		)
		(pad "OB3" smd rect
			(at -5.700014 -29.459936 180)
			(size 0.381 1.4478)
			(layers "F.Cu" "F.Mask" "F.Paste")
			(net "SGPIO_OCP_V3_2_LD_N")
		)
		(pad "OB4" smd rect
			(at -5.700014 -28.859988 180)
			(size 0.381 1.4478)
			(layers "F.Cu" "F.Mask" "F.Paste")
			(net "SGPIO_OCP_V3_2_DATAIN")
		)
		(pad "OB5" smd rect
			(at -5.700014 -28.26004 180)
			(size 0.381 1.4478)
			(layers "F.Cu" "F.Mask" "F.Paste")
			(net "SGPIO_OCP_V3_2_DATAOUT")
		)
		(pad "OB6" smd rect
			(at -5.700014 -27.660092 180)
			(size 0.381 1.4478)
			(layers "F.Cu" "F.Mask" "F.Paste")
			(net "SGPIO_OCP_V3_2_CLK")
		)
		(pad "OB7" smd rect
			(at -5.700014 -27.05989 180)
			(size 0.381 1.4478)
			(layers "F.Cu" "F.Mask" "F.Paste")
			(net "OCP_V3_2_ID0")
		)
		(pad "OB8" smd rect
			(at -5.700014 -26.459942 180)
			(size 0.381 1.4478)
			(layers "F.Cu" "F.Mask" "F.Paste")
			(net "NCSI_OCP_V3_2_RXD1")
		)
		(pad "OB9" smd rect
			(at -5.700014 -25.859994 180)
			(size 0.381 1.4478)
			(layers "F.Cu" "F.Mask" "F.Paste")
			(net "NCSI_OCP_V3_2_RXD0")
		)
		(pad "OB10" smd rect
			(at -5.700014 -25.260046 180)
			(size 0.381 1.4478)
			(layers "F.Cu" "F.Mask" "F.Paste")
			(net "GND")
		)
		(pad "OB11" smd rect
			(at -5.700014 -24.660098 180)
			(size 0.381 1.4478)
			(layers "F.Cu" "F.Mask" "F.Paste")
			(net "CLK_100M_CPU1_CLK04_DN")
		)
		(pad "OB12" smd rect
			(at -5.700014 -24.059896 180)
			(size 0.381 1.4478)
			(layers "F.Cu" "F.Mask" "F.Paste")
			(net "CLK_100M_CPU1_CLK04_DP")
		)
		(pad "OB13" smd rect
			(at -5.700014 -23.459948 180)
			(size 0.381 1.4478)
			(layers "F.Cu" "F.Mask" "F.Paste")
			(net "GND")
		)
		(pad "OB14" smd rect
			(at -5.700014 -22.86 180)
			(size 0.381 1.4478)
			(layers "F.Cu" "F.Mask" "F.Paste")
			(net "NCSI_OCP_V3_2_CRS_DV")
		)
	)
)
